# S9S_MB_2U (Grand Teton) — schematic netlist excerpt (pin names and nets, part order shuffled) for the footprints in the layout excerpt that follows; sources: Cadence DE-HDL packaged netlist, KiCad conversion of 03242023_DA0F0TMBIJ0_F0T_Motherboard_J_brd_V01_OCP.brd

C439  Q_CAP  22UF 4V 20% X6S  pkg C0402  page 77 : A = PVCCFA_EHV_FIVRA_CPU1 ; B = GND

DB9  TDR_3P  EMPTY  pkg TH2  page 309
  GND  = T1_GND
  IO1  = TDR_SE_50_OHM_IN2
  IO2  = TDR_SE_50_OHM_IN2

(kicad_pcb
	(version 20260206)
	(generator "pcbnew")
	(generator_version "10.0")
	(general
		(thickness 1.6)
		(legacy_teardrops no)
	)
	(paper "A4")
	(title_block
		(title "03242023_DA0F0TMBIJ0_F0T_Motherboard_J_brd_V01_OCP.brd")
		(comment 1 "Grand Teton / footprints 2341-2342 of 6105")
	)
	(layers
		(0 "F.Cu" signal "TOP")
		(4 "In1.Cu" signal "GND")
		(6 "In2.Cu" signal "IN1")
		(8 "In3.Cu" signal "GND1")
		(10 "In4.Cu" signal "IN2")
		(12 "In5.Cu" signal "GND2")
		(14 "In6.Cu" signal "IN3")
		(16 "In7.Cu" signal "GND3")
		(18 "In8.Cu" signal "VCC")
		(20 "In9.Cu" signal "VCC1")
		(22 "In10.Cu" signal "GND4")
		(24 "In11.Cu" signal "IN4")
		(26 "In12.Cu" signal "GND5")
		(28 "In13.Cu" signal "IN5")
		(30 "In14.Cu" signal "GND6")
		(32 "In15.Cu" signal "IN6")
		(34 "In16.Cu" signal "GND7")
		(2 "B.Cu" signal "BOTTOM")
		(9 "F.Adhes" user "F.Adhesive")
		(11 "B.Adhes" user "B.Adhesive")
		(13 "F.Paste" user "Package Geometry/Pastemask Top")
		(15 "B.Paste" user "Package Geometry/Pastemask Bottom")
		(5 "F.SilkS" user "Ref Des/Silkscreen Top")
		(7 "B.SilkS" user "Ref Des/Silkscreen Bottom")
		(1 "F.Mask" user "Board Geometry/Soldermask Top")
		(3 "B.Mask" user "Board Geometry/Soldermask Bottom")
		(17 "Dwgs.User" user "User.Drawings")
		(19 "Cmts.User" user "User.Comments")
		(21 "Eco1.User" user "User.Eco1")
		(23 "Eco2.User" user "User.Eco2")
		(25 "Edge.Cuts" user "Board Geometry/Outline")
		(27 "Margin" user)
		(31 "F.CrtYd" user "Package Geometry/Place Bound Top")
		(29 "B.CrtYd" user "Package Geometry/Place Bound Bottom")
		(35 "F.Fab" user "Ref Des/Assembly Top")
		(33 "B.Fab" user "Ref Des/Assembly Bottom")
	)
	(footprint ""
		(layer "F.Cu")
		(at 116.561616 -260.36524 -90)
		(property "Reference" "C439"
			(at 0 0 270)
			(layer "F.SilkS")
			(hide yes)
			(effects
				(font
					(size 1.27 1.27)
				)
			)
		)
		(property "Value" ""
			(at 0 0 270)
			(layer "F.Fab")
			(effects
				(font
					(size 1.27 1.27)
				)
			)
		)
		(duplicate_pad_numbers_are_jumpers no)
		(fp_line
			(start -0.7874 0.4064)
			(end -0.7874 -0.4064)
			(stroke
				(width 0.1524)
				(type default)
			)
			(layer "F.SilkS")
		)
		(fp_line
			(start 0.7874 0.4064)
			(end -0.7874 0.4064)
			(stroke
				(width 0.1524)
				(type default)
			)
			(layer "F.SilkS")
		)
		(fp_line
			(start -0.7874 -0.4064)
			(end 0.7874 -0.4064)
			(stroke
				(width 0.1524)
				(type default)
			)
			(layer "F.SilkS")
		)
		(fp_line
			(start 0.7874 -0.4064)
			(end 0.7874 0.4064)
			(stroke
				(width 0.1524)
				(type default)
			)
			(layer "F.SilkS")
		)
		(fp_line
			(start -0.67945 0.3048)
			(end -0.67945 -0.305054)
			(stroke
				(width 0.1)
				(type default)
			)
			(layer "F.Fab")
		)
		(fp_line
			(start -0.12065 0.3048)
			(end -0.67945 0.3048)
			(stroke
				(width 0.1)
				(type default)
			)
			(layer "F.Fab")
		)
		(fp_line
			(start 0.120396 0.3048)
			(end 0.120396 0.2794)
			(stroke
				(width 0.1)
				(type default)
			)
			(layer "F.Fab")
		)
		(fp_line
			(start 0.67945 0.3048)
			(end 0.120396 0.3048)
			(stroke
				(width 0.1)
				(type default)
			)
			(layer "F.Fab")
		)
		(fp_line
			(start -0.12065 0.2794)
			(end -0.12065 0.3048)
			(stroke
				(width 0.1)
				(type default)
			)
			(layer "F.Fab")
		)
		(fp_line
			(start 0.120396 0.2794)
			(end -0.12065 0.2794)
			(stroke
				(width 0.1)
				(type default)
			)
			(layer "F.Fab")
		)
		(fp_line
			(start -0.12065 -0.2794)
			(end 0.12065 -0.2794)
			(stroke
				(width 0.1)
				(type default)
			)
			(layer "F.Fab")
		)
		(fp_line
			(start 0.12065 -0.2794)
			(end 0.12065 -0.3048)
			(stroke
				(width 0.1)
				(type default)
			)
			(layer "F.Fab")
		)
		(fp_line
			(start 0.12065 -0.3048)
			(end 0.67945 -0.3048)
			(stroke
				(width 0.1)
				(type default)
			)
			(layer "F.Fab")
		)
		(fp_line
			(start 0.67945 -0.3048)
			(end 0.67945 0.3048)
			(stroke
				(width 0.1)
				(type default)
			)
			(layer "F.Fab")
		)
		(fp_line
			(start -0.67945 -0.305054)
			(end -0.12065 -0.305054)
			(stroke
				(width 0.1)
				(type default)
			)
			(layer "F.Fab")
		)
		(fp_line
			(start -0.12065 -0.305054)
			(end -0.12065 -0.2794)
			(stroke
				(width 0.1)
				(type default)
			)
			(layer "F.Fab")
		)
		(pad "1" smd circle
			(at -0.40005 0 270)
			(size 0 0)
			(layers "F.Cu" "F.Mask" "F.Paste")
			(net "PVCCFA_EHV_FIVRA_CPU1")
		)
		(pad "2" smd circle
			(at 0.40005 0 270)
			(size 0 0)
			(layers "F.Cu" "F.Mask" "F.Paste")
			(net "GND")
		)
	)
	(footprint ""
		(layer "F.Cu")
		(at 483.383844 -334.829912 180)
		(property "Reference" "DB9"
			(at -2.448052 0.158496 90)
			(unlocked yes)
			(layer "F.SilkS")
			(effects
				(font
					(size 0.7874 0.5842)
					(thickness 0.1524)
				)
				(justify left)
			)
		)
		(property "Value" ""
			(at 0 0 180)
			(layer "F.Fab")
			(effects
				(font
					(size 1.27 1.27)
				)
			)
		)
		(duplicate_pad_numbers_are_jumpers no)
		(fp_line
			(start 3.330702 -4.771136)
			(end 0 4.011168)
			(stroke
				(width 0.1524)
				(type default)
			)
			(layer "F.SilkS")
		)
		(fp_line
			(start 0 4.011168)
			(end -3.330702 -4.771136)
			(stroke
				(width 0.1524)
				(type default)
			)
			(layer "F.SilkS")
		)
		(fp_line
			(start -3.330702 -4.771136)
			(end 3.330702 -4.771136)
			(stroke
				(width 0.1524)
				(type default)
			)
			(layer "F.SilkS")
		)
		(fp_line
			(start 3.330702 -4.771136)
			(end 0 4.011168)
			(stroke
				(width 0.1)
				(type default)
			)
			(layer "F.Fab")
		)
		(fp_line
			(start 0 4.011168)
			(end -3.330702 -4.771136)
			(stroke
				(width 0.1)
				(type default)
			)
			(layer "F.Fab")
		)
		(fp_line
			(start -3.330702 -4.771136)
			(end 3.330702 -4.771136)
			(stroke
				(width 0.1)
				(type default)
			)
			(layer "F.Fab")
		)
		(pad "1" thru_hole circle
			(at 0 0 180)
			(size 2.159 2.159)
			(drill 1.7018)
			(layers "*.Cu" "*.Mask")
			(remove_unused_layers no)
			(net "T1_GND")
			(clearance 0.0254)
			(thermal_gap 0.0254)
		)
		(pad "2" thru_hole circle
			(at -1.27 -3.348736 180)
			(size 2.159 2.159)
			(drill 1.7018)
			(layers "*.Cu" "*.Mask")
			(remove_unused_layers no)
			(net "TDR_SE_50_OHM_IN2")
			(clearance 0.0254)
			(thermal_gap 0.0254)
		)
		(pad "3" thru_hole circle
			(at 1.27 -3.348736 180)
			(size 2.159 2.159)
			(drill 1.7018)
			(layers "*.Cu" "*.Mask")
			(remove_unused_layers no)
			(net "TDR_SE_50_OHM_IN2")
			(clearance 0.0254)
			(thermal_gap 0.0254)
		)
	)
)
